(kicad_pcb
	(version 20260206)
	(generator "pcbnew")
	(generator_version "10.0")
	(general
		(thickness 1.6)
		(legacy_teardrops no)
	)
	(paper "A4")
	(title_block
		(title "dpb — 14545-sa.0730WZS0815.brd")
		(comment 1 "Honey Badger (Wiwynn) / footprints 442-447 of 1066")
	)
	(layers
		(0 "F.Cu" signal "TOP")
		(4 "In1.Cu" signal "L2GND")
		(6 "In2.Cu" signal "L3")
		(8 "In3.Cu" signal "L4VCC")
		(10 "In4.Cu" signal "L5VCC")
		(12 "In5.Cu" signal "L6")
		(14 "In6.Cu" signal "L7GND")
		(2 "B.Cu" signal "BOTTOM")
		(9 "F.Adhes" user "F.Adhesive")
		(11 "B.Adhes" user "B.Adhesive")
		(13 "F.Paste" user "Package Geometry/Pastemask Top")
		(15 "B.Paste" user "Package Geometry/Pastemask Bottom")
		(5 "F.SilkS" user "Ref Des/Silkscreen Top")
		(7 "B.SilkS" user "Ref Des/Silkscreen Bottom")
		(1 "F.Mask" user "Board Geometry/Soldermask Top")
		(3 "B.Mask" user "Board Geometry/Soldermask Bottom")
		(17 "Dwgs.User" user "User.Drawings")
		(19 "Cmts.User" user "User.Comments")
		(21 "Eco1.User" user "User.Eco1")
		(23 "Eco2.User" user "User.Eco2")
		(25 "Edge.Cuts" user "Board Geometry/Outline")
		(27 "Margin" user)
		(31 "F.CrtYd" user "Package Geometry/Place Bound Top")
		(29 "B.CrtYd" user "Package Geometry/Place Bound Bottom")
		(35 "F.Fab" user "Ref Des/Assembly Top")
		(33 "B.Fab" user "Ref Des/Assembly Bottom")
	)
	(footprint ""
		(layer "F.Cu")
		(at 56.9722 -285.6738 180)
		(property "Reference" "C221"
			(at 0 0 180)
			(layer "F.SilkS")
			(hide yes)
			(effects
				(font
					(size 1.27 1.27)
				)
			)
		)
		(property "Value" "SC10U16V6KX-2GP"
			(at -0.0762 -5.1308 180)
			(unlocked yes)
			(layer "F.Fab")
			(hide yes)
			(effects
				(font
					(size 1.016 1.016)
					(thickness 0.1524)
				)
			)
		)
		(property "Device Type" "C1206H71"
			(at -0.127 -6.6548 180)
			(unlocked yes)
			(layer "F.Fab")
			(hide yes)
			(effects
				(font
					(size 1.016 1.016)
					(thickness 0.1524)
				)
			)
		)
		(duplicate_pad_numbers_are_jumpers no)
		(fp_line
			(start 1.016 2.2352)
			(end -1.016 2.2352)
			(stroke
				(width 0.1524)
				(type default)
			)
			(layer "F.SilkS")
		)
		(fp_line
			(start 1.016 0.8382)
			(end 1.016 2.2352)
			(stroke
				(width 0.1524)
				(type default)
			)
			(layer "F.SilkS")
		)
		(fp_line
			(start 1.016 -2.2352)
			(end 1.016 -0.8382)
			(stroke
				(width 0.1524)
				(type default)
			)
			(layer "F.SilkS")
		)
		(fp_line
			(start -1.016 2.2352)
			(end -1.016 0.8382)
			(stroke
				(width 0.1524)
				(type default)
			)
			(layer "F.SilkS")
		)
		(fp_line
			(start -1.016 -0.8382)
			(end -1.016 -2.2352)
			(stroke
				(width 0.1524)
				(type default)
			)
			(layer "F.SilkS")
		)
		(fp_line
			(start -1.016 -2.2352)
			(end 1.016 -2.2352)
			(stroke
				(width 0.1524)
				(type default)
			)
			(layer "F.SilkS")
		)
		(fp_rect
			(start -1.0922 2.3114)
			(end 1.0922 -2.3114)
			(stroke
				(width 0)
				(type default)
			)
			(fill no)
			(layer "F.CrtYd")
		)
		(fp_poly
			(pts
				(xy 1.0922 -2.3114) (xy 1.0922 2.3114) (xy -1.0922 2.3114) (xy -1.0922 -2.3114)
			)
			(stroke
				(width 0)
				(type default)
			)
			(fill no)
			(layer "F.Fab")
		)
		(pad "1" smd rect
			(at 0 -1.397 180)
			(size 1.651 1.27)
			(layers "F.Cu" "F.Mask" "F.Paste")
			(net "P5V_HDD7")
		)
		(pad "2" smd rect
			(at 0 1.397 180)
			(size 1.651 1.27)
			(layers "F.Cu" "F.Mask" "F.Paste")
			(net "GND")
		)
	)
	(footprint ""
		(layer "F.Cu")
		(at 29.400246 -432.463702 -90)
		(property "Reference" "R246"
			(at 0 0 270)
			(layer "F.SilkS")
			(hide yes)
			(effects
				(font
					(size 1.27 1.27)
				)
			)
		)
		(property "Value" "4K7R2J-2-GP"
			(at 0.064008 -3.993896 270)
			(unlocked yes)
			(layer "F.Fab")
			(hide yes)
			(effects
				(font
					(size 1.016 1.016)
					(thickness 0.1524)
				)
			)
		)
		(property "Device Type" "R402H16"
			(at 0.064008 -5.517896 270)
			(unlocked yes)
			(layer "F.Fab")
			(hide yes)
			(effects
				(font
					(size 1.016 1.016)
					(thickness 0.1524)
				)
			)
		)
		(duplicate_pad_numbers_are_jumpers no)
		(fp_line
			(start -0.508 -0.9398)
			(end -0.508 0.9398)
			(stroke
				(width 0.1524)
				(type default)
			)
			(layer "F.SilkS")
		)
		(fp_line
			(start 0.508 -0.9398)
			(end -0.508 -0.9398)
			(stroke
				(width 0.1524)
				(type default)
			)
			(layer "F.SilkS")
		)
		(fp_rect
			(start -0.508 0.9398)
			(end 0.508 -0.9398)
			(stroke
				(width 0)
				(type default)
			)
			(fill no)
			(layer "F.CrtYd")
		)
		(fp_rect
			(start -0.508 0.9398)
			(end 0.508 -0.9398)
			(stroke
				(width 0)
				(type default)
			)
			(fill no)
			(layer "F.Fab")
		)
		(pad "1" smd custom
			(at 0 -0.4445 270)
			(size 0.1397 0.1397)
			(layers "F.Cu" "F.Mask" "F.Paste")
			(net "P3V3")
			(options
				(clearance outline)
				(anchor circle)
			)
			(primitives
				(gr_poly
					(pts
						(arc
							(start -0.1778 -0.2794)
							(mid -0.249642 -0.249642)
							(end -0.2794 -0.1778)
						)
						(arc
							(start -0.2794 0.1778)
							(mid -0.249642 0.249642)
							(end -0.1778 0.2794)
						)
						(arc
							(start 0.1778 0.2794)
							(mid 0.249642 0.249642)
							(end 0.2794 0.1778)
						)
						(arc
							(start 0.2794 -0.1778)
							(mid 0.249642 -0.249642)
							(end 0.1778 -0.2794)
						)
					)
					(width 0)
					(fill yes)
				)
			)
		)
		(pad "2" smd custom
			(at 0 0.4445 270)
			(size 0.1397 0.1397)
			(layers "F.Cu" "F.Mask" "F.Paste")
			(net "HDD_PRSNT_NET10")
			(options
				(clearance outline)
				(anchor circle)
			)
			(primitives
				(gr_poly
					(pts
						(arc
							(start -0.1778 -0.2794)
							(mid -0.249642 -0.249642)
							(end -0.2794 -0.1778)
						)
						(arc
							(start -0.2794 0.1778)
							(mid -0.249642 0.249642)
							(end -0.1778 0.2794)
						)
						(arc
							(start 0.1778 0.2794)
							(mid 0.249642 0.249642)
							(end 0.2794 0.1778)
						)
						(arc
							(start 0.2794 -0.1778)
							(mid 0.249642 -0.249642)
							(end 0.1778 -0.2794)
						)
					)
					(width 0)
					(fill yes)
				)
			)
		)
	)
	(footprint ""
		(layer "F.Cu")
		(at 234.753912 -41.763696 90)
		(property "Reference" "R160"
			(at 0 0 90)
			(layer "F.SilkS")
			(hide yes)
			(effects
				(font
					(size 1.27 1.27)
				)
			)
		)
		(property "Value" "0R2J-2-GP"
			(at 0.064008 -3.993896 90)
			(unlocked yes)
			(layer "F.Fab")
			(hide yes)
			(effects
				(font
					(size 1.016 1.016)
					(thickness 0.1524)
				)
			)
		)
		(property "Device Type" "R402H16"
			(at 0.064008 -5.517896 90)
			(unlocked yes)
			(layer "F.Fab")
			(hide yes)
			(effects
				(font
					(size 1.016 1.016)
					(thickness 0.1524)
				)
			)
		)
		(duplicate_pad_numbers_are_jumpers no)
		(fp_line
			(start 0.508 -0.9398)
			(end -0.508 -0.9398)
			(stroke
				(width 0.1524)
				(type default)
			)
			(layer "F.SilkS")
		)
		(fp_line
			(start -0.508 -0.9398)
			(end -0.508 0.9398)
			(stroke
				(width 0.1524)
				(type default)
			)
			(layer "F.SilkS")
		)
		(fp_rect
			(start -0.508 0.9398)
			(end 0.508 -0.9398)
			(stroke
				(width 0)
				(type default)
			)
			(fill no)
			(layer "F.CrtYd")
		)
		(fp_rect
			(start -0.508 0.9398)
			(end 0.508 -0.9398)
			(stroke
				(width 0)
				(type default)
			)
			(fill no)
			(layer "F.Fab")
		)
		(pad "1" smd custom
			(at 0 -0.4445 90)
			(size 0.1397 0.1397)
			(layers "F.Cu" "F.Mask" "F.Paste")
			(net "FLT_NET_HDD4")
			(options
				(clearance outline)
				(anchor circle)
			)
			(primitives
				(gr_poly
					(pts
						(arc
							(start -0.1778 -0.2794)
							(mid -0.249642 -0.249642)
							(end -0.2794 -0.1778)
						)
						(arc
							(start -0.2794 0.1778)
							(mid -0.249642 0.249642)
							(end -0.1778 0.2794)
						)
						(arc
							(start 0.1778 0.2794)
							(mid 0.249642 0.249642)
							(end 0.2794 0.1778)
						)
						(arc
							(start 0.2794 -0.1778)
							(mid 0.249642 -0.249642)
							(end 0.1778 -0.2794)
						)
					)
					(width 0)
					(fill yes)
				)
			)
		)
		(pad "2" smd custom
			(at 0 0.4445 90)
			(size 0.1397 0.1397)
			(layers "F.Cu" "F.Mask" "F.Paste")
			(net "FLT_HDD4_DRIVE")
			(options
				(clearance outline)
				(anchor circle)
			)
			(primitives
				(gr_poly
					(pts
						(arc
							(start -0.1778 -0.2794)
							(mid -0.249642 -0.249642)
							(end -0.2794 -0.1778)
						)
						(arc
							(start -0.2794 0.1778)
							(mid -0.249642 0.249642)
							(end -0.1778 0.2794)
						)
						(arc
							(start 0.1778 0.2794)
							(mid 0.249642 0.249642)
							(end 0.2794 0.1778)
						)
						(arc
							(start 0.2794 -0.1778)
							(mid 0.249642 -0.249642)
							(end 0.1778 -0.2794)
						)
					)
					(width 0)
					(fill yes)
				)
			)
		)
	)
	(footprint ""
		(layer "F.Cu")
		(at 60.3885 -275.74875 -90)
		(property "Reference" "Q61"
			(at 0 0 270)
			(layer "F.SilkS")
			(hide yes)
			(effects
				(font
					(size 1.27 1.27)
				)
			)
		)
		(property "Value" "2N7002-11-GP"
			(at 0.127 -8.9662 270)
			(unlocked yes)
			(layer "F.Fab")
			(hide yes)
			(effects
				(font
					(size 1.016 1.016)
					(thickness 0.1524)
				)
			)
		)
		(property "Device Type" "SOT23DGS2D4H44"
			(at 0.127 -10.4902 270)
			(unlocked yes)
			(layer "F.Fab")
			(hide yes)
			(effects
				(font
					(size 1.016 1.016)
					(thickness 0.1524)
				)
			)
		)
		(duplicate_pad_numbers_are_jumpers no)
		(fp_line
			(start -1.651 1.778)
			(end 1.651 1.778)
			(stroke
				(width 0.1524)
				(type default)
			)
			(layer "F.SilkS")
		)
		(fp_line
			(start 1.651 1.778)
			(end 1.651 -1.778)
			(stroke
				(width 0.1524)
				(type default)
			)
			(layer "F.SilkS")
		)
		(fp_line
			(start -1.651 -1.778)
			(end -1.651 1.778)
			(stroke
				(width 0.1524)
				(type default)
			)
			(layer "F.SilkS")
		)
		(fp_line
			(start 1.651 -1.778)
			(end -1.651 -1.778)
			(stroke
				(width 0.1524)
				(type default)
			)
			(layer "F.SilkS")
		)
		(fp_poly
			(pts
				(xy -1.778 1.8796) (xy -1.778 -1.8796) (xy 1.778 -1.8796) (xy 1.778 1.8796)
			)
			(stroke
				(width 0)
				(type default)
			)
			(fill no)
			(layer "F.CrtYd")
		)
		(fp_poly
			(pts
				(xy -1.778 1.8796) (xy -1.778 -1.8796) (xy 1.778 -1.8796) (xy 1.778 1.8796)
			)
			(stroke
				(width 0)
				(type default)
			)
			(fill no)
			(layer "F.Fab")
		)
		(pad "D" smd custom
			(at 0 -0.9525 270)
			(size 0.1905 0.1905)
			(layers "F.Cu" "F.Mask" "F.Paste")
			(net "HDD7_LED_G")
			(options
				(clearance outline)
				(anchor circle)
			)
			(primitives
				(gr_poly
					(pts
						(arc
							(start -0.1778 0.5715)
							(mid -0.321484 0.511984)
							(end -0.381 0.3683)
						)
						(arc
							(start -0.381 -0.3683)
							(mid -0.321484 -0.511984)
							(end -0.1778 -0.5715)
						)
						(arc
							(start 0.1778 -0.5715)
							(mid 0.321484 -0.511984)
							(end 0.381 -0.3683)
						)
						(arc
							(start 0.381 0.3683)
							(mid 0.321484 0.511984)
							(end 0.1778 0.5715)
						)
					)
					(width 0)
					(fill yes)
				)
			)
		)
		(pad "G" smd custom
			(at -0.98425 0.9525 270)
			(size 0.1905 0.1905)
			(layers "F.Cu" "F.Mask" "F.Paste")
			(net "HDD7_LED_B")
			(options
				(clearance outline)
				(anchor circle)
			)
			(primitives
				(gr_poly
					(pts
						(arc
							(start -0.1778 0.5715)
							(mid -0.321484 0.511984)
							(end -0.381 0.3683)
						)
						(arc
							(start -0.381 -0.3683)
							(mid -0.321484 -0.511984)
							(end -0.1778 -0.5715)
						)
						(arc
							(start 0.1778 -0.5715)
							(mid 0.321484 -0.511984)
							(end 0.381 -0.3683)
						)
						(arc
							(start 0.381 0.3683)
							(mid 0.321484 0.511984)
							(end 0.1778 0.5715)
						)
					)
					(width 0)
					(fill yes)
				)
			)
		)
		(pad "S" smd custom
			(at 0.98425 0.9525 270)
			(size 0.1905 0.1905)
			(layers "F.Cu" "F.Mask" "F.Paste")
			(net "GND")
			(options
				(clearance outline)
				(anchor circle)
			)
			(primitives
				(gr_poly
					(pts
						(arc
							(start -0.1778 0.5715)
							(mid -0.321484 0.511984)
							(end -0.381 0.3683)
						)
						(arc
							(start -0.381 -0.3683)
							(mid -0.321484 -0.511984)
							(end -0.1778 -0.5715)
						)
						(arc
							(start 0.1778 -0.5715)
							(mid 0.321484 -0.511984)
							(end 0.381 -0.3683)
						)
						(arc
							(start 0.381 0.3683)
							(mid 0.321484 0.511984)
							(end 0.1778 0.5715)
						)
					)
					(width 0)
					(fill yes)
				)
			)
		)
	)
	(footprint ""
		(layer "F.Cu")
		(at 35.813746 -116.487702)
		(property "Reference" "C320"
			(at 0 0 0)
			(layer "F.SilkS")
			(hide yes)
			(effects
				(font
					(size 1.27 1.27)
				)
			)
		)
		(property "Value" "SC10U25V6KX-1GP"
			(at -0.0762 -5.1308 0)
			(unlocked yes)
			(layer "F.Fab")
			(hide yes)
			(effects
				(font
					(size 1.016 1.016)
					(thickness 0.1524)
				)
			)
		)
		(property "Device Type" "C1206H71"
			(at -0.127 -6.6548 0)
			(unlocked yes)
			(layer "F.Fab")
			(hide yes)
			(effects
				(font
					(size 1.016 1.016)
					(thickness 0.1524)
				)
			)
		)
		(duplicate_pad_numbers_are_jumpers no)
		(fp_line
			(start -1.016 -2.2352)
			(end 1.016 -2.2352)
			(stroke
				(width 0.1524)
				(type default)
			)
			(layer "F.SilkS")
		)
		(fp_line
			(start -1.016 -0.8382)
			(end -1.016 -2.2352)
			(stroke
				(width 0.1524)
				(type default)
			)
			(layer "F.SilkS")
		)
		(fp_line
			(start -1.016 2.2352)
			(end -1.016 0.8382)
			(stroke
				(width 0.1524)
				(type default)
			)
			(layer "F.SilkS")
		)
		(fp_line
			(start 1.016 -2.2352)
			(end 1.016 -0.8382)
			(stroke
				(width 0.1524)
				(type default)
			)
			(layer "F.SilkS")
		)
		(fp_line
			(start 1.016 0.8382)
			(end 1.016 2.2352)
			(stroke
				(width 0.1524)
				(type default)
			)
			(layer "F.SilkS")
		)
		(fp_line
			(start 1.016 2.2352)
			(end -1.016 2.2352)
			(stroke
				(width 0.1524)
				(type default)
			)
			(layer "F.SilkS")
		)
		(fp_rect
			(start -1.0922 2.3114)
			(end 1.0922 -2.3114)
			(stroke
				(width 0)
				(type default)
			)
			(fill no)
			(layer "F.CrtYd")
		)
		(fp_poly
			(pts
				(xy 1.0922 -2.3114) (xy 1.0922 2.3114) (xy -1.0922 2.3114) (xy -1.0922 -2.3114)
			)
			(stroke
				(width 0)
				(type default)
			)
			(fill no)
			(layer "F.Fab")
		)
		(pad "1" smd rect
			(at 0 -1.397)
			(size 1.651 1.27)
			(layers "F.Cu" "F.Mask" "F.Paste")
			(net "P12V_HDD13")
		)
		(pad "2" smd rect
			(at 0 1.397)
			(size 1.651 1.27)
			(layers "F.Cu" "F.Mask" "F.Paste")
			(net "GND")
		)
	)
	(footprint ""
		(layer "F.Cu")
		(at 56.514746 -234.343702)
		(property "Reference" "Q25"
			(at 0 0 0)
			(layer "F.SilkS")
			(hide yes)
			(effects
				(font
					(size 1.27 1.27)
				)
			)
		)
		(property "Value" "AO4406AL-GP"
			(at -3.707384 -1.5367 0)
			(unlocked yes)
			(layer "F.Fab")
			(hide yes)
			(effects
				(font
					(size 1.016 1.016)
					(thickness 0.1524)
				)
			)
		)
		(property "Device Type" "SOIC8H69"
			(at -3.707384 -3.0607 0)
			(unlocked yes)
			(layer "F.Fab")
			(hide yes)
			(effects
				(font
					(size 1.016 1.016)
					(thickness 0.1524)
				)
			)
		)
		(duplicate_pad_numbers_are_jumpers no)
		(fp_line
			(start -2.7432 -1.4224)
			(end -2.7432 1.4224)
			(stroke
				(width 0.1524)
				(type default)
			)
			(layer "F.SilkS")
		)
		(fp_line
			(start -2.7432 1.4224)
			(end -2.6416 1.4224)
			(stroke
				(width 0.1524)
				(type default)
			)
			(layer "F.SilkS")
		)
		(fp_line
			(start -2.7432 1.4224)
			(end 2.1336 1.4224)
			(stroke
				(width 0.1524)
				(type default)
			)
			(layer "F.SilkS")
		)
		(fp_line
			(start -2.7178 -0.508)
			(end -2.1844 -0.0508)
			(stroke
				(width 0.1524)
				(type default)
			)
			(layer "F.SilkS")
		)
		(fp_line
			(start -2.6289 3.4417)
			(end -2.6289 1.4732)
			(stroke
				(width 0.381)
				(type default)
			)
			(layer "F.SilkS")
		)
		(fp_line
			(start -2.1844 -0.0508)
			(end -2.7178 0.508)
			(stroke
				(width 0.1524)
				(type default)
			)
			(layer "F.SilkS")
		)
		(fp_line
			(start 2.1336 -1.4224)
			(end -2.7432 -1.4224)
			(stroke
				(width 0.1524)
				(type default)
			)
			(layer "F.SilkS")
		)
		(fp_line
			(start 2.1336 1.4224)
			(end 2.1336 -1.4224)
			(stroke
				(width 0.1524)
				(type default)
			)
			(layer "F.SilkS")
		)
		(fp_poly
			(pts
				(xy -2.2098 -1.4224) (xy -2.2098 1.4224) (xy 2.2098 1.4224) (xy 2.2098 -1.4224)
			)
			(stroke
				(width 0)
				(type default)
			)
			(fill yes)
			(layer "F.SilkS")
		)
		(fp_rect
			(start -2.450084 2.999994)
			(end 2.450084 -2.999994)
			(stroke
				(width 0)
				(type default)
			)
			(fill no)
			(layer "F.CrtYd")
		)
		(fp_poly
			(pts
				(xy -2.8194 3.6322) (xy -2.8194 -3.6322) (xy 2.8194 -3.6322) (xy 2.8194 1.18364) (xy 2.450084 1.18364)
				(xy 2.450084 -2.999994) (xy -2.450084 -2.999994) (xy -2.450084 2.999994) (xy 2.450084 2.999994)
				(xy 2.450084 1.18618) (xy 2.8194 1.18618) (xy 2.8194 3.6322)
			)
			(stroke
				(width 0)
				(type default)
			)
			(fill no)
			(layer "F.CrtYd")
		)
		(fp_rect
			(start -2.8194 3.6322)
			(end 2.8194 -3.6322)
			(stroke
				(width 0)
				(type default)
			)
			(fill no)
			(layer "F.Fab")
		)
		(pad "1" smd rect
			(at -1.905 2.54)
			(size 0.635 1.651)
			(layers "F.Cu" "F.Mask" "F.Paste")
			(net "P5V_HDD12")
		)
		(pad "2" smd rect
			(at -0.635 2.54)
			(size 0.635 1.651)
			(layers "F.Cu" "F.Mask" "F.Paste")
			(net "P5V_HDD12")
		)
		(pad "3" smd rect
			(at 0.635 2.54)
			(size 0.635 1.651)
			(layers "F.Cu" "F.Mask" "F.Paste")
			(net "P5V_HDD12")
		)
		(pad "4" smd rect
			(at 1.905 2.54)
			(size 0.635 1.651)
			(layers "F.Cu" "F.Mask" "F.Paste")
			(net "SW_HDD12_P")
		)
		(pad "5" smd rect
			(at 1.905 -2.54)
			(size 0.635 1.651)
			(layers "F.Cu" "F.Mask" "F.Paste")
			(net "P5VC")
		)
		(pad "6" smd rect
			(at 0.635 -2.54)
			(size 0.635 1.651)
			(layers "F.Cu" "F.Mask" "F.Paste")
			(net "P5VC")
		)
		(pad "7" smd rect
			(at -0.635 -2.54)
			(size 0.635 1.651)
			(layers "F.Cu" "F.Mask" "F.Paste")
			(net "P5VC")
		)
		(pad "8" smd rect
			(at -1.905 -2.54)
			(size 0.635 1.651)
			(layers "F.Cu" "F.Mask" "F.Paste")
			(net "P5VC")
		)
	)
)
